(kicad_pcb
	(version 20241229)
	(generator "pcbnew")
	(generator_version "9.0")
	(general
		(thickness 1.711)
		(legacy_teardrops no)
	)
	(paper "A4")
	(title_block
		(title "Antmicro Baseboard for Jetson AGX Thor")
		(date "2026-02-18")
		(rev "1.1.0")
		(company "Antmicro Ltd")
		(comment 1 "www.antmicro.com")
		(comment 9 "footprints 957-960 of 1170")
	)
	(layers
		(0 "F.Cu" signal)
		(4 "In1.Cu" signal)
		(6 "In2.Cu" signal)
		(8 "In3.Cu" signal)
		(10 "In4.Cu" jumper)
		(12 "In5.Cu" signal)
		(14 "In6.Cu" signal)
		(16 "In7.Cu" signal)
		(18 "In8.Cu" signal)
		(2 "B.Cu" signal)
		(9 "F.Adhes" user "F.Adhesive")
		(11 "B.Adhes" user "B.Adhesive")
		(13 "F.Paste" user)
		(15 "B.Paste" user)
		(5 "F.SilkS" user "F.Silkscreen")
		(7 "B.SilkS" user "B.Silkscreen")
		(1 "F.Mask" user)
		(3 "B.Mask" user)
		(17 "Dwgs.User" user "User.Drawings")
		(19 "Cmts.User" user "User.Comments")
		(21 "Eco1.User" user "User.Eco1")
		(23 "Eco2.User" user "User.Eco2")
		(25 "Edge.Cuts" user)
		(27 "Margin" user)
		(31 "F.CrtYd" user "F.Courtyard")
		(29 "B.CrtYd" user "B.Courtyard")
		(35 "F.Fab" user)
		(33 "B.Fab" user)
	)
	(footprint "antmicro-footprints:R_0402_1005Metric"
		(layer "B.Cu")
		(at 223.5 56.25 180)
		(descr "Resistor SMD 0402")
		(tags "resistor SMD 0402")
		(property "Reference" "R178"
			(at -3 -2.65 0)
			(layer "B.SilkS")
			(effects
				(font
					(size 0.7 0.7)
					(thickness 0.15)
				)
				(justify left bottom mirror)
			)
		)
		(property "Value" "R_470R_0402"
			(at -1.011843 -1.772046 0)
			(layer "B.Fab")
			(effects
				(font
					(size 0.7 0.7)
					(thickness 0.15)
				)
				(justify left bottom mirror)
			)
		)
		(property "Datasheet" "https://www.bourns.com/docs/product-datasheets/cr.pdf"
			(at 0 0 0)
			(layer "B.Fab")
			(hide yes)
			(effects
				(font
					(size 1.27 1.27)
					(thickness 0.15)
				)
				(justify mirror)
			)
		)
		(property "Description" "SMD Chip Resistor, 470 ohm, ± 1%, 62.5 mW, 0402 [1005 Metric], Thick Film, General Purpose"
			(at 0 0 0)
			(layer "B.Fab")
			(hide yes)
			(effects
				(font
					(size 1.27 1.27)
					(thickness 0.15)
				)
				(justify mirror)
			)
		)
		(property "Manufacturer" "Bourns"
			(at 0 0 0)
			(unlocked yes)
			(layer "B.Fab")
			(hide yes)
			(effects
				(font
					(size 1 1)
					(thickness 0.15)
				)
				(justify mirror)
			)
		)
		(property "MPN" "CR0402-FX-4700GLF"
			(at 0 0 0)
			(unlocked yes)
			(layer "B.Fab")
			(hide yes)
			(effects
				(font
					(size 1 1)
					(thickness 0.15)
				)
				(justify mirror)
			)
		)
		(property "Val" "470R"
			(at 0 0 0)
			(unlocked yes)
			(layer "B.Fab")
			(hide yes)
			(effects
				(font
					(size 1 1)
					(thickness 0.15)
				)
				(justify mirror)
			)
		)
		(property "License" "Apache-2.0"
			(at 0 0 0)
			(unlocked yes)
			(layer "B.Fab")
			(hide yes)
			(effects
				(font
					(size 1 1)
					(thickness 0.15)
				)
				(justify mirror)
			)
		)
		(property "Author" "Antmicro"
			(at 0 0 0)
			(unlocked yes)
			(layer "B.Fab")
			(hide yes)
			(effects
				(font
					(size 1 1)
					(thickness 0.15)
				)
				(justify mirror)
			)
		)
		(property "Tolerance" "1%"
			(at 0 0 0)
			(unlocked yes)
			(layer "B.Fab")
			(hide yes)
			(effects
				(font
					(size 1 1)
					(thickness 0.15)
				)
				(justify mirror)
			)
		)
		(sheetname "/CSI/")
		(sheetfile "csi.kicad_sch")
		(attr smd)
		(fp_poly
			(pts
				(xy -0.925 0.47) (xy -0.925 -0.47) (xy 0.925 -0.47) (xy 0.925 0.47)
			)
			(stroke
				(width 0.05)
				(type default)
			)
			(fill no)
			(layer "B.CrtYd")
		)
		(fp_poly
			(pts
				(xy -0.5 0.25) (xy -0.5 -0.25) (xy 0.5 -0.25) (xy 0.5 0.25)
			)
			(stroke
				(width 0.15)
				(type solid)
			)
			(fill no)
			(layer "B.Fab")
		)
		(fp_text user "Author: Antmicro"
			(at -0.95 -4.169 0)
			(layer "B.Fab")
			(effects
				(font
					(size 0.7 0.7)
					(thickness 0.15)
				)
				(justify left bottom mirror)
			)
		)
		(fp_text user "License: Apache-2.0"
			(at -0.949999 -5.169 0)
			(layer "B.Fab")
			(effects
				(font
					(size 0.7 0.7)
					(thickness 0.15)
				)
				(justify left bottom mirror)
			)
		)
		(fp_text user "${REFERENCE}"
			(at -0.95 -3.168 0)
			(layer "B.Fab")
			(effects
				(font
					(size 0.7 0.7)
					(thickness 0.15)
				)
				(justify left bottom mirror)
			)
		)
		(pad "1" smd roundrect
			(at -0.48 0 180)
			(size 0.59 0.64)
			(layers "B.Cu" "B.Mask" "B.Paste")
			(roundrect_rratio 0.25)
			(net 540 "Net-(D27-A)")
			(pintype "passive")
		)
		(pad "2" smd roundrect
			(at 0.48 0 180)
			(size 0.59 0.64)
			(layers "B.Cu" "B.Mask" "B.Paste")
			(roundrect_rratio 0.25)
			(net 9 "/CSI/CSIB_5V")
			(pintype "passive")
		)
	)
	(footprint "antmicro-footprints:C_0402_1005Metric"
		(layer "B.Cu")
		(at 126.5635 142.81 180)
		(descr "Capacitor SMD 0402")
		(tags "capacitor SMD 0402")
		(property "Reference" "C203"
			(at 1.060532 -0.52 0)
			(layer "B.SilkS")
			(effects
				(font
					(size 0.7 0.7)
					(thickness 0.15)
				)
				(justify left bottom mirror)
			)
		)
		(property "Value" "C_100n_0402"
			(at -1.022927 -2.155213 0)
			(layer "B.Fab")
			(effects
				(font
					(size 0.7 0.7)
					(thickness 0.15)
				)
				(justify left bottom mirror)
			)
		)
		(property "Datasheet" "https://www.murata.com/products/productdetail?partno=GRM155R61H104KE14%23"
			(at 0 0 0)
			(layer "B.Fab")
			(hide yes)
			(effects
				(font
					(size 1.27 1.27)
					(thickness 0.15)
				)
				(justify mirror)
			)
		)
		(property "Description" "SMD Multilayer Ceramic Capacitor, 0.1 µF, 50 V, 0402 [1005 Metric], ± 10%, X5R, GRM Series"
			(at 0 0 0)
			(layer "B.Fab")
			(hide yes)
			(effects
				(font
					(size 1.27 1.27)
					(thickness 0.15)
				)
				(justify mirror)
			)
		)
		(property "MPN" "GRM155R61H104KE14D"
			(at 0 0 0)
			(unlocked yes)
			(layer "B.Fab")
			(hide yes)
			(effects
				(font
					(size 1 1)
					(thickness 0.15)
				)
				(justify mirror)
			)
		)
		(property "Val" "100n"
			(at 0 0 0)
			(unlocked yes)
			(layer "B.Fab")
			(hide yes)
			(effects
				(font
					(size 1 1)
					(thickness 0.15)
				)
				(justify mirror)
			)
		)
		(property "Voltage" "50V"
			(at 0 0 0)
			(unlocked yes)
			(layer "B.Fab")
			(hide yes)
			(effects
				(font
					(size 1 1)
					(thickness 0.15)
				)
				(justify mirror)
			)
		)
		(property "Dielectric" "X5R"
			(at 0 0 0)
			(unlocked yes)
			(layer "B.Fab")
			(hide yes)
			(effects
				(font
					(size 1 1)
					(thickness 0.15)
				)
				(justify mirror)
			)
		)
		(property "Manufacturer" "Murata"
			(at 0 0 0)
			(unlocked yes)
			(layer "B.Fab")
			(hide yes)
			(effects
				(font
					(size 1 1)
					(thickness 0.15)
				)
				(justify mirror)
			)
		)
		(property "License" "Apache-2.0"
			(at 0 0 0)
			(unlocked yes)
			(layer "B.Fab")
			(hide yes)
			(effects
				(font
					(size 1 1)
					(thickness 0.15)
				)
				(justify mirror)
			)
		)
		(property "Author" "Antmicro"
			(at 0 0 0)
			(unlocked yes)
			(layer "B.Fab")
			(hide yes)
			(effects
				(font
					(size 1 1)
					(thickness 0.15)
				)
				(justify mirror)
			)
		)
		(sheetname "/Peripherals/")
		(sheetfile "peripherals.kicad_sch")
		(attr smd)
		(fp_rect
			(start -0.925 0.47)
			(end 0.925 -0.47)
			(stroke
				(width 0.05)
				(type default)
			)
			(fill no)
			(layer "B.CrtYd")
		)
		(fp_line
			(start 0.504 0.25)
			(end 0.504 -0.248)
			(stroke
				(width 0.15)
				(type solid)
			)
			(layer "B.Fab")
		)
		(fp_line
			(start 0.504 -0.248)
			(end -0.494 -0.248)
			(stroke
				(width 0.15)
				(type solid)
			)
			(layer "B.Fab")
		)
		(fp_line
			(start -0.494 0.25)
			(end 0.504 0.25)
			(stroke
				(width 0.15)
				(type solid)
			)
			(layer "B.Fab")
		)
		(fp_line
			(start -0.494 -0.248)
			(end -0.494 0.25)
			(stroke
				(width 0.15)
				(type solid)
			)
			(layer "B.Fab")
		)
		(fp_text user "License: Apache-2.0"
			(at -0.939 -5.799 0)
			(layer "B.Fab")
			(effects
				(font
					(size 0.7 0.7)
					(thickness 0.15)
				)
				(justify left bottom mirror)
			)
		)
		(fp_text user "Author: Antmicro"
			(at -0.939 -3.399 0)
			(layer "B.Fab")
			(effects
				(font
					(size 0.7 0.7)
					(thickness 0.15)
				)
				(justify left bottom mirror)
			)
		)
		(fp_text user "${REFERENCE}"
			(at -0.939 -4.599 0)
			(layer "B.Fab")
			(effects
				(font
					(size 0.7 0.7)
					(thickness 0.15)
				)
				(justify left bottom mirror)
			)
		)
		(pad "1" smd roundrect
			(at -0.48 0 180)
			(size 0.59 0.64)
			(layers "B.Cu" "B.Mask" "B.Paste")
			(roundrect_rratio 0.25)
			(net 1 "GND")
			(pintype "passive")
		)
		(pad "2" smd roundrect
			(at 0.48 0 180)
			(size 0.59 0.64)
			(layers "B.Cu" "B.Mask" "B.Paste")
			(roundrect_rratio 0.25)
			(net 2 "+3V3")
			(pintype "passive")
		)
	)
	(footprint "antmicro-footprints:DHVQFN-14-1EP_2.5x3mm"
		(layer "B.Cu")
		(at 160.33 67.24 180)
		(property "Reference" "U59"
			(at -1.27 -4.16 90)
			(layer "B.SilkS")
			(effects
				(font
					(size 0.7 0.7)
					(thickness 0.15)
				)
				(justify right top mirror)
			)
		)
		(property "Value" "TXU0304BQAR"
			(at 0 -2.898 0)
			(layer "B.Fab")
			(effects
				(font
					(size 0.7 0.7)
					(thickness 0.15)
				)
				(justify left bottom mirror)
			)
		)
		(property "Datasheet" "https://www.ti.com/lit/ds/symlink/txu0304.pdf?ts=1637748643258&ref_url=https%253A%252F%252Fwww.ti.com%252Fproduct%252FTXU0304"
			(at 0 0 0)
			(layer "B.Fab")
			(hide yes)
			(effects
				(font
					(size 1.27 1.27)
					(thickness 0.15)
				)
				(justify mirror)
			)
		)
		(property "Description" "Logic translator/level shifter"
			(at 0 0 0)
			(layer "B.Fab")
			(hide yes)
			(effects
				(font
					(size 1.27 1.27)
					(thickness 0.15)
				)
				(justify mirror)
			)
		)
		(property "MPN" "TXU0304BQAR"
			(at 0 0 0)
			(unlocked yes)
			(layer "B.Fab")
			(hide yes)
			(effects
				(font
					(size 1 1)
					(thickness 0.15)
				)
				(justify mirror)
			)
		)
		(property "Manufacturer" "Texas Instruments"
			(at 0 0 0)
			(unlocked yes)
			(layer "B.Fab")
			(hide yes)
			(effects
				(font
					(size 1 1)
					(thickness 0.15)
				)
				(justify mirror)
			)
		)
		(property "Author" "Antmicro"
			(at 0 0 0)
			(unlocked yes)
			(layer "B.Fab")
			(hide yes)
			(effects
				(font
					(size 1 1)
					(thickness 0.15)
				)
				(justify mirror)
			)
		)
		(property "License" "Apache-2.0"
			(at 0 0 0)
			(unlocked yes)
			(layer "B.Fab")
			(hide yes)
			(effects
				(font
					(size 1 1)
					(thickness 0.15)
				)
				(justify mirror)
			)
		)
		(sheetname "/SoM_IO2/")
		(sheetfile "som_io2.kicad_sch")
		(attr smd exclude_from_pos_files exclude_from_bom dnp)
		(fp_line
			(start 1.35 1.601)
			(end 1.35 1.25)
			(stroke
				(width 0.15)
				(type solid)
			)
			(layer "B.SilkS")
		)
		(fp_line
			(start 1.35 1.601)
			(end 0.494 1.601)
			(stroke
				(width 0.15)
				(type solid)
			)
			(layer "B.SilkS")
		)
		(fp_line
			(start 1.35 -1.6)
			(end 1.35 -1.249)
			(stroke
				(width 0.15)
				(type solid)
			)
			(layer "B.SilkS")
		)
		(fp_line
			(start 0.494 -1.6)
			(end 1.35 -1.6)
			(stroke
				(width 0.15)
				(type solid)
			)
			(layer "B.SilkS")
		)
		(fp_line
			(start -1.35 1.601)
			(end -1.35 1.25)
			(stroke
				(width 0.15)
				(type solid)
			)
			(layer "B.SilkS")
		)
		(fp_line
			(start -1.351 1.601)
			(end -0.5 1.601)
			(stroke
				(width 0.15)
				(type solid)
			)
			(layer "B.SilkS")
		)
		(fp_line
			(start -1.351 -1.6)
			(end -0.5 -1.6)
			(stroke
				(width 0.15)
				(type solid)
			)
			(layer "B.SilkS")
		)
		(fp_line
			(start -1.351 -1.6)
			(end -1.351 -1.249)
			(stroke
				(width 0.15)
				(type solid)
			)
			(layer "B.SilkS")
		)
		(fp_circle
			(center -0.7 1.85)
			(end -0.653 1.85)
			(stroke
				(width 0.15)
				(type solid)
			)
			(fill yes)
			(layer "B.SilkS")
		)
		(fp_rect
			(start -1.85 2)
			(end 1.8 -1.95)
			(stroke
				(width 0.05)
				(type solid)
			)
			(fill no)
			(layer "B.CrtYd")
		)
		(fp_line
			(start 1.249 1.5)
			(end 1.249 -1.499)
			(stroke
				(width 0.15)
				(type solid)
			)
			(layer "B.Fab")
		)
		(fp_line
			(start 1.249 -1.499)
			(end -1.25 -1.499)
			(stroke
				(width 0.15)
				(type solid)
			)
			(layer "B.Fab")
		)
		(fp_line
			(start -1 1.5)
			(end 1.249 1.5)
			(stroke
				(width 0.15)
				(type solid)
			)
			(layer "B.Fab")
		)
		(fp_line
			(start -1.25 1.25)
			(end -1 1.5)
			(stroke
				(width 0.15)
				(type solid)
			)
			(layer "B.Fab")
		)
		(fp_line
			(start -1.25 -1.499)
			(end -1.25 1.25)
			(stroke
				(width 0.15)
				(type solid)
			)
			(layer "B.Fab")
		)
		(fp_text user "License: Apache-2.0"
			(at -1.841 -6.097 0)
			(layer "B.Fab")
			(effects
				(font
					(size 0.7 0.7)
					(thickness 0.15)
				)
				(justify left bottom mirror)
			)
		)
		(fp_text user "${REFERENCE}"
			(at -1.841 -4.897 0)
			(layer "B.Fab")
			(effects
				(font
					(size 0.7 0.7)
					(thickness 0.15)
				)
				(justify left bottom mirror)
			)
		)
		(fp_text user "Author: Antmicro"
			(at -1.841 -7.296 0)
			(layer "B.Fab")
			(effects
				(font
					(size 0.7 0.7)
					(thickness 0.15)
				)
				(justify left bottom mirror)
			)
		)
		(pad "1" smd oval
			(at -0.25 1.5 180)
			(size 0.3 0.8)
			(layers "B.Cu" "B.Mask" "B.Paste")
			(net 269 "/SoM_IO2/TC_VCC")
			(pinfunction "VCCA")
			(pintype "power_in")
		)
		(pad "2" smd oval
			(at -1.25 1 90)
			(size 0.3 0.8)
			(layers "B.Cu" "B.Mask" "B.Paste")
			(net 869 "/SoM_IO2/TC_JTAG_TMS")
			(pinfunction "A1")
			(pintype "input")
		)
		(pad "3" smd oval
			(at -1.25 0.5 90)
			(size 0.3 0.8)
			(layers "B.Cu" "B.Mask" "B.Paste")
			(net 868 "/SoM_IO2/TC_JTAG_TDI")
			(pinfunction "A2")
			(pintype "input")
		)
		(pad "4" smd oval
			(at -1.25 0 90)
			(size 0.3 0.8)
			(layers "B.Cu" "B.Mask" "B.Paste")
			(net 871 "/SoM_IO2/TC_JTAG_TCK")
			(pinfunction "A3")
			(pintype "input")
		)
		(pad "5" smd oval
			(at -1.25 -0.494 90)
			(size 0.3 0.8)
			(layers "B.Cu" "B.Mask" "B.Paste")
			(net 872 "/SoM_IO2/TC_JTAG_TDO")
			(pinfunction "A4Y")
			(pintype "output")
		)
		(pad "6" smd oval
			(at -1.25 -0.994 90)
			(size 0.3 0.8)
			(layers "B.Cu" "B.Mask" "B.Paste")
			(net 1124 "unconnected-(U59-NC-Pad6)")
			(pinfunction "NC")
			(pintype "no_connect")
		)
		(pad "7" smd oval
			(at -0.25 -1.499 180)
			(size 0.3 0.8)
			(layers "B.Cu" "B.Mask" "B.Paste")
			(net 1 "GND")
			(pinfunction "GND")
			(pintype "passive")
		)
		(pad "8" smd oval
			(at 0.244 -1.499 180)
			(size 0.3 0.8)
			(layers "B.Cu" "B.Mask" "B.Paste")
			(net 11 "+1V8")
			(pinfunction "OE")
			(pintype "tri_state")
		)
		(pad "9" smd oval
			(at 1.249 -0.994 90)
			(size 0.3 0.8)
			(layers "B.Cu" "B.Mask" "B.Paste")
			(net 1123 "unconnected-(U59-NC-Pad9)")
			(pinfunction "NC")
			(pintype "no_connect")
		)
		(pad "10" smd oval
			(at 1.249 -0.494 90)
			(size 0.3 0.8)
			(layers "B.Cu" "B.Mask" "B.Paste")
			(net 1031 "Net-(U59-B4)")
			(pinfunction "B4")
			(pintype "input")
		)
		(pad "11" smd oval
			(at 1.249 0 90)
			(size 0.3 0.8)
			(layers "B.Cu" "B.Mask" "B.Paste")
			(net 1028 "Net-(U59-B3Y)")
			(pinfunction "B3Y")
			(pintype "output")
		)
		(pad "12" smd oval
			(at 1.249 0.5 90)
			(size 0.3 0.8)
			(layers "B.Cu" "B.Mask" "B.Paste")
			(net 1029 "Net-(U59-B2Y)")
			(pinfunction "B2Y")
			(pintype "output")
		)
		(pad "13" smd oval
			(at 1.249 1 90)
			(size 0.3 0.8)
			(layers "B.Cu" "B.Mask" "B.Paste")
			(net 1030 "Net-(U59-B1Y)")
			(pinfunction "B1Y")
			(pintype "output")
		)
		(pad "14" smd oval
			(at 0.244 1.5 180)
			(size 0.3 0.8)
			(layers "B.Cu" "B.Mask" "B.Paste")
			(net 11 "+1V8")
			(pinfunction "VCCB")
			(pintype "power_in")
		)
		(pad "15" smd rect
			(at 0 0 180)
			(size 1 1.5)
			(layers "B.Cu" "B.Mask" "B.Paste")
			(net 1 "GND")
			(pinfunction "GND")
			(pintype "power_in")
		)
	)
	(footprint "antmicro-footprints:C_0402_1005Metric"
		(layer "B.Cu")
		(at 207 61.512999 180)
		(descr "Capacitor SMD 0402")
		(tags "capacitor SMD 0402")
		(property "Reference" "C159"
			(at 0.89 -0.42 0)
			(layer "B.SilkS")
			(effects
				(font
					(size 0.7 0.7)
					(thickness 0.15)
				)
				(justify left bottom mirror)
			)
		)
		(property "Value" "C_100n_0402"
			(at -1.022927 -2.155213 0)
			(layer "B.Fab")
			(effects
				(font
					(size 0.7 0.7)
					(thickness 0.15)
				)
				(justify left bottom mirror)
			)
		)
		(property "Datasheet" "https://www.murata.com/products/productdetail?partno=GRM155R61H104KE14%23"
			(at 0 0 0)
			(layer "B.Fab")
			(hide yes)
			(effects
				(font
					(size 1.27 1.27)
					(thickness 0.15)
				)
				(justify mirror)
			)
		)
		(property "Description" "SMD Multilayer Ceramic Capacitor, 0.1 µF, 50 V, 0402 [1005 Metric], ± 10%, X5R, GRM Series"
			(at 0 0 0)
			(layer "B.Fab")
			(hide yes)
			(effects
				(font
					(size 1.27 1.27)
					(thickness 0.15)
				)
				(justify mirror)
			)
		)
		(property "Manufacturer" "Murata"
			(at 0 0 0)
			(unlocked yes)
			(layer "B.Fab")
			(hide yes)
			(effects
				(font
					(size 1 1)
					(thickness 0.15)
				)
				(justify mirror)
			)
		)
		(property "MPN" "GRM155R61H104KE14D"
			(at 0 0 0)
			(unlocked yes)
			(layer "B.Fab")
			(hide yes)
			(effects
				(font
					(size 1 1)
					(thickness 0.15)
				)
				(justify mirror)
			)
		)
		(property "Val" "100n"
			(at 0 0 0)
			(unlocked yes)
			(layer "B.Fab")
			(hide yes)
			(effects
				(font
					(size 1 1)
					(thickness 0.15)
				)
				(justify mirror)
			)
		)
		(property "License" "Apache-2.0"
			(at 0 0 0)
			(unlocked yes)
			(layer "B.Fab")
			(hide yes)
			(effects
				(font
					(size 1 1)
					(thickness 0.15)
				)
				(justify mirror)
			)
		)
		(property "Author" "Antmicro"
			(at 0 0 0)
			(unlocked yes)
			(layer "B.Fab")
			(hide yes)
			(effects
				(font
					(size 1 1)
					(thickness 0.15)
				)
				(justify mirror)
			)
		)
		(property "Voltage" "50V"
			(at 0 0 0)
			(unlocked yes)
			(layer "B.Fab")
			(hide yes)
			(effects
				(font
					(size 1 1)
					(thickness 0.15)
				)
				(justify mirror)
			)
		)
		(property "Dielectric" "X5R"
			(at 0 0 0)
			(unlocked yes)
			(layer "B.Fab")
			(hide yes)
			(effects
				(font
					(size 1 1)
					(thickness 0.15)
				)
				(justify mirror)
			)
		)
		(sheetname "/CSI/")
		(sheetfile "csi.kicad_sch")
		(attr smd)
		(fp_poly
			(pts
				(xy -0.925 0.47) (xy -0.925 -0.47) (xy 0.925 -0.47) (xy 0.925 0.47)
			)
			(stroke
				(width 0.05)
				(type default)
			)
			(fill no)
			(layer "B.CrtYd")
		)
		(fp_line
			(start 0.504 0.25)
			(end 0.504 -0.248)
			(stroke
				(width 0.15)
				(type solid)
			)
			(layer "B.Fab")
		)
		(fp_line
			(start 0.504 -0.248)
			(end -0.494 -0.248)
			(stroke
				(width 0.15)
				(type solid)
			)
			(layer "B.Fab")
		)
		(fp_line
			(start -0.494 0.25)
			(end 0.504 0.25)
			(stroke
				(width 0.15)
				(type solid)
			)
			(layer "B.Fab")
		)
		(fp_line
			(start -0.494 -0.248)
			(end -0.494 0.25)
			(stroke
				(width 0.15)
				(type solid)
			)
			(layer "B.Fab")
		)
		(fp_text user "License: Apache-2.0"
			(at -0.939 -5.799 0)
			(layer "B.Fab")
			(effects
				(font
					(size 0.7 0.7)
					(thickness 0.15)
				)
				(justify left bottom mirror)
			)
		)
		(fp_text user "Author: Antmicro"
			(at -0.939 -3.399 0)
			(layer "B.Fab")
			(effects
				(font
					(size 0.7 0.7)
					(thickness 0.15)
				)
				(justify left bottom mirror)
			)
		)
		(fp_text user "${REFERENCE}"
			(at -0.939 -4.599 0)
			(layer "B.Fab")
			(effects
				(font
					(size 0.7 0.7)
					(thickness 0.15)
				)
				(justify left bottom mirror)
			)
		)
		(pad "1" smd roundrect
			(at -0.48 0 180)
			(size 0.59 0.64)
			(layers "B.Cu" "B.Mask" "B.Paste")
			(roundrect_rratio 0.25)
			(net 2 "+3V3")
			(pintype "passive")
		)
		(pad "2" smd roundrect
			(at 0.48 0 180)
			(size 0.59 0.64)
			(layers "B.Cu" "B.Mask" "B.Paste")
			(roundrect_rratio 0.25)
			(net 1 "GND")
			(pintype "passive")
		)
	)
)
